(kicad_pcb
	(version 20260206)
	(generator "pcbnew")
	(generator_version "10.0")
	(general
		(thickness 1.6)
		(legacy_teardrops no)
	)
	(paper "A4")
	(title_block
		(title "baseboard — 13948-1b.1110WZS1818.brd")
		(comment 1 "Honey Badger (Wiwynn) / footprints 2424-2431 of 2523")
	)
	(layers
		(0 "F.Cu" signal "TOP")
		(4 "In1.Cu" signal "L2GND")
		(6 "In2.Cu" signal "L3")
		(8 "In3.Cu" signal "L4VCC")
		(10 "In4.Cu" signal "L5VCC")
		(12 "In5.Cu" signal "L6")
		(14 "In6.Cu" signal "L7GND")
		(2 "B.Cu" signal "BOTTOM")
		(9 "F.Adhes" user "F.Adhesive")
		(11 "B.Adhes" user "B.Adhesive")
		(13 "F.Paste" user "Package Geometry/Pastemask Top")
		(15 "B.Paste" user "Package Geometry/Pastemask Bottom")
		(5 "F.SilkS" user "Ref Des/Silkscreen Top")
		(7 "B.SilkS" user "Ref Des/Silkscreen Bottom")
		(1 "F.Mask" user "Board Geometry/Soldermask Top")
		(3 "B.Mask" user "Board Geometry/Soldermask Bottom")
		(17 "Dwgs.User" user "User.Drawings")
		(19 "Cmts.User" user "User.Comments")
		(21 "Eco1.User" user "User.Eco1")
		(23 "Eco2.User" user "User.Eco2")
		(25 "Edge.Cuts" user "Board Geometry/Outline")
		(27 "Margin" user)
		(31 "F.CrtYd" user "Package Geometry/Place Bound Top")
		(29 "B.CrtYd" user "Package Geometry/Place Bound Bottom")
		(35 "F.Fab" user "Ref Des/Assembly Top")
		(33 "B.Fab" user "Ref Des/Assembly Bottom")
	)
	(footprint ""
		(layer "B.Cu")
		(at 122.428 -33.528)
		(property "Reference" "SC933"
			(at 0 0 0)
			(layer "B.SilkS")
			(hide yes)
			(effects
				(font
					(size 1.27 1.27)
				)
				(justify mirror)
			)
		)
		(property "Value" "SC1U6D3V1MX-GP"
			(at -1.9177 2.0193 0)
			(unlocked yes)
			(layer "B.Fab")
			(hide yes)
			(effects
				(font
					(size 1.016 1.016)
					(thickness 0.1524)
				)
				(justify mirror)
			)
		)
		(property "Device Type" "C0201H14"
			(at -1.9177 0.4953 0)
			(unlocked yes)
			(layer "B.Fab")
			(hide yes)
			(effects
				(font
					(size 1.016 1.016)
					(thickness 0.1524)
				)
				(justify mirror)
			)
		)
		(duplicate_pad_numbers_are_jumpers no)
		(fp_rect
			(start 0.1524 0.3048)
			(end -0.1524 -0.3048)
			(stroke
				(width 0)
				(type default)
			)
			(fill no)
			(layer "B.CrtYd")
		)
		(fp_poly
			(pts
				(xy 0.2794 0.6477) (xy 0.2794 -0.6477) (xy -0.2794 -0.6477) (xy -0.2794 -0.1905) (xy -0.1524 -0.1905)
				(xy -0.1524 -0.3048) (xy 0.1524 -0.3048) (xy 0.1524 0.3048) (xy -0.1524 0.3048) (xy -0.1524 -0.1778)
				(xy -0.2794 -0.1778) (xy -0.2794 0.6477)
			)
			(stroke
				(width 0)
				(type default)
			)
			(fill no)
			(layer "B.CrtYd")
		)
		(fp_rect
			(start 0.2794 0.6477)
			(end -0.2794 -0.6477)
			(stroke
				(width 0)
				(type default)
			)
			(fill no)
			(layer "B.Fab")
		)
		(pad "1" smd custom
			(at 0 -0.2794 180)
			(size 0.0762 0.0762)
			(layers "B.Cu" "B.Mask" "B.Paste")
			(net "PLL_VDD")
			(options
				(clearance outline)
				(anchor circle)
			)
			(primitives
				(gr_poly
					(pts
						(arc
							(start 0.1524 0.127)
							(mid 0.137521 0.162921)
							(end 0.1016 0.1778)
						)
						(arc
							(start -0.1016 0.1778)
							(mid -0.137521 0.162921)
							(end -0.1524 0.127)
						)
						(arc
							(start -0.1524 -0.127)
							(mid -0.137521 -0.162921)
							(end -0.1016 -0.1778)
						)
						(arc
							(start 0.1016 -0.1778)
							(mid 0.137521 -0.162921)
							(end 0.1524 -0.127)
						)
					)
					(width 0)
					(fill yes)
				)
			)
		)
		(pad "2" smd custom
			(at 0 0.2794 180)
			(size 0.0762 0.0762)
			(layers "B.Cu" "B.Mask" "B.Paste")
			(net "GND")
			(options
				(clearance outline)
				(anchor circle)
			)
			(primitives
				(gr_poly
					(pts
						(arc
							(start 0.1524 0.127)
							(mid 0.137521 0.162921)
							(end 0.1016 0.1778)
						)
						(arc
							(start -0.1016 0.1778)
							(mid -0.137521 0.162921)
							(end -0.1524 0.127)
						)
						(arc
							(start -0.1524 -0.127)
							(mid -0.137521 -0.162921)
							(end -0.1016 -0.1778)
						)
						(arc
							(start 0.1016 -0.1778)
							(mid 0.137521 -0.162921)
							(end 0.1524 -0.127)
						)
					)
					(width 0)
					(fill yes)
				)
			)
		)
	)
	(footprint ""
		(layer "B.Cu")
		(at 46.68393 -79.174086)
		(property "Reference" "TP185"
			(at 0 0 0)
			(layer "B.SilkS")
			(hide yes)
			(effects
				(font
					(size 1.27 1.27)
				)
				(justify mirror)
			)
		)
		(property "Value" "TPAD32-GP"
			(at 0 -3.166364 0)
			(unlocked yes)
			(layer "B.Fab")
			(hide yes)
			(effects
				(font
					(size 1.016 1.016)
					(thickness 0.1524)
				)
				(justify mirror)
			)
		)
		(property "Device Type" "TPAD32"
			(at 0 -4.690618 0)
			(unlocked yes)
			(layer "B.Fab")
			(hide yes)
			(effects
				(font
					(size 1.016 1.016)
					(thickness 0.1524)
				)
				(justify mirror)
			)
		)
		(duplicate_pad_numbers_are_jumpers no)
		(fp_poly
			(pts
				(arc
					(start 0.4064 0)
					(mid -0.4064 0)
					(end 0.4064 0)
				)
			)
			(stroke
				(width 0)
				(type default)
			)
			(fill no)
			(layer "B.CrtYd")
		)
		(fp_poly
			(pts
				(arc
					(start 0.7112 0)
					(mid -0.7112 0)
					(end 0.7112 0)
				)
			)
			(stroke
				(width 0)
				(type default)
			)
			(fill no)
			(layer "B.Fab")
		)
		(pad "1" smd circle
			(at 0 0 180)
			(size 0.8128 0.8128)
			(layers "B.Cu" "B.Mask" "B.Paste")
			(net "INT_CONN_A_SB0")
		)
	)
	(footprint ""
		(layer "B.Cu")
		(at 296.790872 -177.872136 -90)
		(property "Reference" "C205"
			(at 0 0 90)
			(layer "B.SilkS")
			(hide yes)
			(effects
				(font
					(size 1.27 1.27)
				)
				(justify mirror)
			)
		)
		(property "Value" "SC1U10V2KX-1GP"
			(at -1.1811 -2.7051 270)
			(unlocked yes)
			(layer "B.Fab")
			(hide yes)
			(effects
				(font
					(size 1.016 1.016)
					(thickness 0.1524)
				)
				(justify mirror)
			)
		)
		(property "Device Type" "C402H22"
			(at -1.1811 -4.2291 270)
			(unlocked yes)
			(layer "B.Fab")
			(hide yes)
			(effects
				(font
					(size 1.016 1.016)
					(thickness 0.1524)
				)
				(justify mirror)
			)
		)
		(duplicate_pad_numbers_are_jumpers no)
		(fp_rect
			(start 0.4318 0.9525)
			(end -0.4318 -0.9525)
			(stroke
				(width 0)
				(type default)
			)
			(fill no)
			(layer "B.CrtYd")
		)
		(fp_rect
			(start 0.4318 0.9525)
			(end -0.4318 -0.9525)
			(stroke
				(width 0)
				(type default)
			)
			(fill no)
			(layer "B.Fab")
		)
		(pad "1" smd custom
			(at 0 -0.4445 90)
			(size 0.1524 0.1524)
			(layers "B.Cu" "B.Mask" "B.Paste")
			(net "P1V26_STBY")
			(options
				(clearance outline)
				(anchor circle)
			)
			(primitives
				(gr_poly
					(pts
						(arc
							(start 0.3048 0.2032)
							(mid 0.275042 0.275042)
							(end 0.2032 0.3048)
						)
						(arc
							(start -0.2032 0.3048)
							(mid -0.275042 0.275042)
							(end -0.3048 0.2032)
						)
						(arc
							(start -0.3048 -0.2032)
							(mid -0.275042 -0.275042)
							(end -0.2032 -0.3048)
						)
						(arc
							(start 0.2032 -0.3048)
							(mid 0.275042 -0.275042)
							(end 0.3048 -0.2032)
						)
					)
					(width 0)
					(fill yes)
				)
			)
		)
		(pad "2" smd custom
			(at 0 0.4445 90)
			(size 0.1524 0.1524)
			(layers "B.Cu" "B.Mask" "B.Paste")
			(net "GND")
			(options
				(clearance outline)
				(anchor circle)
			)
			(primitives
				(gr_poly
					(pts
						(arc
							(start 0.3048 0.2032)
							(mid 0.275042 0.275042)
							(end 0.2032 0.3048)
						)
						(arc
							(start -0.2032 0.3048)
							(mid -0.275042 0.275042)
							(end -0.3048 0.2032)
						)
						(arc
							(start -0.3048 -0.2032)
							(mid -0.275042 -0.275042)
							(end -0.2032 -0.3048)
						)
						(arc
							(start 0.2032 -0.3048)
							(mid 0.275042 -0.275042)
							(end 0.3048 -0.2032)
						)
					)
					(width 0)
					(fill yes)
				)
			)
		)
	)
	(footprint ""
		(layer "B.Cu")
		(at 91.648026 -53.09616)
		(property "Reference" "SC1016"
			(at 0 0 0)
			(layer "B.SilkS")
			(hide yes)
			(effects
				(font
					(size 1.27 1.27)
				)
				(justify mirror)
			)
		)
		(property "Value" "SC1KP50V2KX-1GP"
			(at -1.1811 -2.7051 0)
			(unlocked yes)
			(layer "B.Fab")
			(hide yes)
			(effects
				(font
					(size 1.016 1.016)
					(thickness 0.1524)
				)
				(justify mirror)
			)
		)
		(property "Device Type" "C402H22"
			(at -1.1811 -4.2291 0)
			(unlocked yes)
			(layer "B.Fab")
			(hide yes)
			(effects
				(font
					(size 1.016 1.016)
					(thickness 0.1524)
				)
				(justify mirror)
			)
		)
		(duplicate_pad_numbers_are_jumpers no)
		(fp_rect
			(start 0.4318 0.9525)
			(end -0.4318 -0.9525)
			(stroke
				(width 0)
				(type default)
			)
			(fill no)
			(layer "B.CrtYd")
		)
		(fp_rect
			(start 0.4318 0.9525)
			(end -0.4318 -0.9525)
			(stroke
				(width 0)
				(type default)
			)
			(fill no)
			(layer "B.Fab")
		)
		(pad "1" smd custom
			(at 0 -0.4445 180)
			(size 0.1524 0.1524)
			(layers "B.Cu" "B.Mask" "B.Paste")
			(net "P1V8_C")
			(options
				(clearance outline)
				(anchor circle)
			)
			(primitives
				(gr_poly
					(pts
						(arc
							(start 0.3048 0.2032)
							(mid 0.275042 0.275042)
							(end 0.2032 0.3048)
						)
						(arc
							(start -0.2032 0.3048)
							(mid -0.275042 0.275042)
							(end -0.3048 0.2032)
						)
						(arc
							(start -0.3048 -0.2032)
							(mid -0.275042 -0.275042)
							(end -0.2032 -0.3048)
						)
						(arc
							(start 0.2032 -0.3048)
							(mid 0.275042 -0.275042)
							(end 0.3048 -0.2032)
						)
					)
					(width 0)
					(fill yes)
				)
			)
		)
		(pad "2" smd custom
			(at 0 0.4445 180)
			(size 0.1524 0.1524)
			(layers "B.Cu" "B.Mask" "B.Paste")
			(net "GND")
			(options
				(clearance outline)
				(anchor circle)
			)
			(primitives
				(gr_poly
					(pts
						(arc
							(start 0.3048 0.2032)
							(mid 0.275042 0.275042)
							(end 0.2032 0.3048)
						)
						(arc
							(start -0.2032 0.3048)
							(mid -0.275042 0.275042)
							(end -0.3048 0.2032)
						)
						(arc
							(start -0.3048 -0.2032)
							(mid -0.275042 -0.275042)
							(end -0.2032 -0.3048)
						)
						(arc
							(start 0.2032 -0.3048)
							(mid 0.275042 -0.275042)
							(end 0.3048 -0.2032)
						)
					)
					(width 0)
					(fill yes)
				)
			)
		)
	)
	(footprint ""
		(layer "B.Cu")
		(at 318.008 -180.721 -90)
		(property "Reference" "R322"
			(at 0 0 90)
			(layer "B.SilkS")
			(hide yes)
			(effects
				(font
					(size 1.27 1.27)
				)
				(justify mirror)
			)
		)
		(property "Value" "0R2J-2-GP"
			(at -0.064008 -3.993896 270)
			(unlocked yes)
			(layer "B.Fab")
			(hide yes)
			(effects
				(font
					(size 1.016 1.016)
					(thickness 0.1524)
				)
				(justify mirror)
			)
		)
		(property "Device Type" "R402H16"
			(at -0.064008 -5.517896 270)
			(unlocked yes)
			(layer "B.Fab")
			(hide yes)
			(effects
				(font
					(size 1.016 1.016)
					(thickness 0.1524)
				)
				(justify mirror)
			)
		)
		(duplicate_pad_numbers_are_jumpers no)
		(fp_line
			(start -0.508 -0.9398)
			(end 0.508 -0.9398)
			(stroke
				(width 0.1524)
				(type default)
			)
			(layer "B.SilkS")
		)
		(fp_line
			(start 0.508 -0.9398)
			(end 0.508 0.9398)
			(stroke
				(width 0.1524)
				(type default)
			)
			(layer "B.SilkS")
		)
		(fp_rect
			(start 0.508 0.9398)
			(end -0.508 -0.9398)
			(stroke
				(width 0)
				(type default)
			)
			(fill no)
			(layer "B.CrtYd")
		)
		(fp_rect
			(start 0.508 0.9398)
			(end -0.508 -0.9398)
			(stroke
				(width 0)
				(type default)
			)
			(fill no)
			(layer "B.Fab")
		)
		(pad "1" smd custom
			(at 0 -0.4445 90)
			(size 0.1397 0.1397)
			(layers "B.Cu" "B.Mask" "B.Paste")
			(net "ADC_P0V9_E")
			(options
				(clearance outline)
				(anchor circle)
			)
			(primitives
				(gr_poly
					(pts
						(arc
							(start -0.1778 0.2794)
							(mid -0.249642 0.249642)
							(end -0.2794 0.1778)
						)
						(arc
							(start -0.2794 -0.1778)
							(mid -0.249642 -0.249642)
							(end -0.1778 -0.2794)
						)
						(arc
							(start 0.1778 -0.2794)
							(mid 0.249642 -0.249642)
							(end 0.2794 -0.1778)
						)
						(arc
							(start 0.2794 0.1778)
							(mid 0.249642 0.249642)
							(end 0.1778 0.2794)
						)
					)
					(width 0)
					(fill yes)
				)
			)
		)
		(pad "2" smd custom
			(at 0 0.4445 90)
			(size 0.1397 0.1397)
			(layers "B.Cu" "B.Mask" "B.Paste")
			(net "ADC_P0V9_E_BMC")
			(options
				(clearance outline)
				(anchor circle)
			)
			(primitives
				(gr_poly
					(pts
						(arc
							(start -0.1778 0.2794)
							(mid -0.249642 0.249642)
							(end -0.2794 0.1778)
						)
						(arc
							(start -0.2794 -0.1778)
							(mid -0.249642 -0.249642)
							(end -0.1778 -0.2794)
						)
						(arc
							(start 0.1778 -0.2794)
							(mid 0.249642 -0.249642)
							(end 0.2794 -0.1778)
						)
						(arc
							(start 0.2794 0.1778)
							(mid 0.249642 0.249642)
							(end 0.1778 0.2794)
						)
					)
					(width 0)
					(fill yes)
				)
			)
		)
	)
	(footprint ""
		(layer "B.Cu")
		(at 113.29797 -82.931 -90)
		(property "Reference" "SC1233"
			(at 0 0 90)
			(layer "B.SilkS")
			(hide yes)
			(effects
				(font
					(size 1.27 1.27)
				)
				(justify mirror)
			)
		)
		(property "Value" "SCD1U6D3V1KX-GP"
			(at 2.8321 -1.7399 270)
			(unlocked yes)
			(layer "B.Fab")
			(hide yes)
			(effects
				(font
					(size 1.016 1.016)
					(thickness 0.1524)
				)
				(justify mirror)
			)
		)
		(property "Device Type" "C0201H13"
			(at 2.8321 -3.2639 270)
			(unlocked yes)
			(layer "B.Fab")
			(hide yes)
			(effects
				(font
					(size 1.016 1.016)
					(thickness 0.1524)
				)
				(justify mirror)
			)
		)
		(duplicate_pad_numbers_are_jumpers no)
		(fp_rect
			(start 0.2794 0.6477)
			(end -0.2794 -0.6477)
			(stroke
				(width 0)
				(type default)
			)
			(fill no)
			(layer "B.CrtYd")
		)
		(fp_rect
			(start 0.2794 0.6477)
			(end -0.2794 -0.6477)
			(stroke
				(width 0)
				(type default)
			)
			(fill no)
			(layer "B.Fab")
		)
		(pad "1" smd custom
			(at 0 -0.2794 90)
			(size 0.0762 0.0762)
			(layers "B.Cu" "B.Mask" "B.Paste")
			(net "P1V8_E")
			(options
				(clearance outline)
				(anchor circle)
			)
			(primitives
				(gr_poly
					(pts
						(arc
							(start 0.1524 0.127)
							(mid 0.137521 0.162921)
							(end 0.1016 0.1778)
						)
						(arc
							(start -0.1016 0.1778)
							(mid -0.137521 0.162921)
							(end -0.1524 0.127)
						)
						(arc
							(start -0.1524 -0.127)
							(mid -0.137521 -0.162921)
							(end -0.1016 -0.1778)
						)
						(arc
							(start 0.1016 -0.1778)
							(mid 0.137521 -0.162921)
							(end 0.1524 -0.127)
						)
					)
					(width 0)
					(fill yes)
				)
			)
		)
		(pad "2" smd custom
			(at 0 0.2794 90)
			(size 0.0762 0.0762)
			(layers "B.Cu" "B.Mask" "B.Paste")
			(net "GND")
			(options
				(clearance outline)
				(anchor circle)
			)
			(primitives
				(gr_poly
					(pts
						(arc
							(start 0.1524 0.127)
							(mid 0.137521 0.162921)
							(end 0.1016 0.1778)
						)
						(arc
							(start -0.1016 0.1778)
							(mid -0.137521 0.162921)
							(end -0.1524 0.127)
						)
						(arc
							(start -0.1524 -0.127)
							(mid -0.137521 -0.162921)
							(end -0.1016 -0.1778)
						)
						(arc
							(start 0.1016 -0.1778)
							(mid 0.137521 -0.162921)
							(end 0.1524 -0.127)
						)
					)
					(width 0)
					(fill yes)
				)
			)
		)
	)
	(footprint ""
		(layer "B.Cu")
		(at 81.661 -21.209 180)
		(property "Reference" "PR184"
			(at 0 0 0)
			(layer "B.SilkS")
			(hide yes)
			(effects
				(font
					(size 1.27 1.27)
				)
				(justify mirror)
			)
		)
		(property "Value" "10KR2F-2-GP"
			(at -0.064008 -3.993896 180)
			(unlocked yes)
			(layer "B.Fab")
			(hide yes)
			(effects
				(font
					(size 1.016 1.016)
					(thickness 0.1524)
				)
				(justify mirror)
			)
		)
		(property "Device Type" "R402H16"
			(at -0.064008 -5.517896 180)
			(unlocked yes)
			(layer "B.Fab")
			(hide yes)
			(effects
				(font
					(size 1.016 1.016)
					(thickness 0.1524)
				)
				(justify mirror)
			)
		)
		(duplicate_pad_numbers_are_jumpers no)
		(fp_line
			(start 0.508 -0.9398)
			(end 0.508 0.9398)
			(stroke
				(width 0.1524)
				(type default)
			)
			(layer "B.SilkS")
		)
		(fp_line
			(start -0.508 -0.9398)
			(end 0.508 -0.9398)
			(stroke
				(width 0.1524)
				(type default)
			)
			(layer "B.SilkS")
		)
		(fp_rect
			(start 0.508 0.9398)
			(end -0.508 -0.9398)
			(stroke
				(width 0)
				(type default)
			)
			(fill no)
			(layer "B.CrtYd")
		)
		(fp_rect
			(start 0.508 0.9398)
			(end -0.508 -0.9398)
			(stroke
				(width 0)
				(type default)
			)
			(fill no)
			(layer "B.Fab")
		)
		(pad "1" smd custom
			(at 0 -0.4445)
			(size 0.1397 0.1397)
			(layers "B.Cu" "B.Mask" "B.Paste")
			(net "AGND_P0V9_C")
			(options
				(clearance outline)
				(anchor circle)
			)
			(primitives
				(gr_poly
					(pts
						(arc
							(start -0.1778 0.2794)
							(mid -0.249642 0.249642)
							(end -0.2794 0.1778)
						)
						(arc
							(start -0.2794 -0.1778)
							(mid -0.249642 -0.249642)
							(end -0.1778 -0.2794)
						)
						(arc
							(start 0.1778 -0.2794)
							(mid 0.249642 -0.249642)
							(end 0.2794 -0.1778)
						)
						(arc
							(start 0.2794 0.1778)
							(mid 0.249642 0.249642)
							(end 0.1778 0.2794)
						)
					)
					(width 0)
					(fill yes)
				)
			)
		)
		(pad "2" smd custom
			(at 0 0.4445)
			(size 0.1397 0.1397)
			(layers "B.Cu" "B.Mask" "B.Paste")
			(net "VT235_IMAX")
			(options
				(clearance outline)
				(anchor circle)
			)
			(primitives
				(gr_poly
					(pts
						(arc
							(start -0.1778 0.2794)
							(mid -0.249642 0.249642)
							(end -0.2794 0.1778)
						)
						(arc
							(start -0.2794 -0.1778)
							(mid -0.249642 -0.249642)
							(end -0.1778 -0.2794)
						)
						(arc
							(start 0.1778 -0.2794)
							(mid 0.249642 -0.249642)
							(end 0.2794 -0.1778)
						)
						(arc
							(start 0.2794 0.1778)
							(mid 0.249642 0.249642)
							(end 0.1778 0.2794)
						)
					)
					(width 0)
					(fill yes)
				)
			)
		)
	)
	(footprint ""
		(layer "B.Cu")
		(at 165.354 -114.427 180)
		(property "Reference" "SR855"
			(at 0 0 0)
			(layer "B.SilkS")
			(hide yes)
			(effects
				(font
					(size 1.27 1.27)
				)
				(justify mirror)
			)
		)
		(property "Value" "10KR2F-2-GP"
			(at -0.064008 -3.993896 180)
			(unlocked yes)
			(layer "B.Fab")
			(hide yes)
			(effects
				(font
					(size 1.016 1.016)
					(thickness 0.1524)
				)
				(justify mirror)
			)
		)
		(property "Device Type" "R402H16"
			(at -0.064008 -5.517896 180)
			(unlocked yes)
			(layer "B.Fab")
			(hide yes)
			(effects
				(font
					(size 1.016 1.016)
					(thickness 0.1524)
				)
				(justify mirror)
			)
		)
		(duplicate_pad_numbers_are_jumpers no)
		(fp_line
			(start 0.508 -0.9398)
			(end 0.508 0.9398)
			(stroke
				(width 0.1524)
				(type default)
			)
			(layer "B.SilkS")
		)
		(fp_line
			(start -0.508 -0.9398)
			(end 0.508 -0.9398)
			(stroke
				(width 0.1524)
				(type default)
			)
			(layer "B.SilkS")
		)
		(fp_rect
			(start 0.508 0.9398)
			(end -0.508 -0.9398)
			(stroke
				(width 0)
				(type default)
			)
			(fill no)
			(layer "B.CrtYd")
		)
		(fp_rect
			(start 0.508 0.9398)
			(end -0.508 -0.9398)
			(stroke
				(width 0)
				(type default)
			)
			(fill no)
			(layer "B.Fab")
		)
		(pad "1" smd custom
			(at 0 -0.4445)
			(size 0.1397 0.1397)
			(layers "B.Cu" "B.Mask" "B.Paste")
			(net "P3V3_STBY_R4")
			(options
				(clearance outline)
				(anchor circle)
			)
			(primitives
				(gr_poly
					(pts
						(arc
							(start -0.1778 0.2794)
							(mid -0.249642 0.249642)
							(end -0.2794 0.1778)
						)
						(arc
							(start -0.2794 -0.1778)
							(mid -0.249642 -0.249642)
							(end -0.1778 -0.2794)
						)
						(arc
							(start 0.1778 -0.2794)
							(mid 0.249642 -0.249642)
							(end 0.2794 -0.1778)
						)
						(arc
							(start 0.2794 0.1778)
							(mid 0.249642 0.249642)
							(end 0.1778 0.2794)
						)
					)
					(width 0)
					(fill yes)
				)
			)
		)
		(pad "2" smd custom
			(at 0 0.4445)
			(size 0.1397 0.1397)
			(layers "B.Cu" "B.Mask" "B.Paste")
			(net "P3V3_STBY_G4")
			(options
				(clearance outline)
				(anchor circle)
			)
			(primitives
				(gr_poly
					(pts
						(arc
							(start -0.1778 0.2794)
							(mid -0.249642 0.249642)
							(end -0.2794 0.1778)
						)
						(arc
							(start -0.2794 -0.1778)
							(mid -0.249642 -0.249642)
							(end -0.1778 -0.2794)
						)
						(arc
							(start 0.1778 -0.2794)
							(mid 0.249642 -0.249642)
							(end 0.2794 -0.1778)
						)
						(arc
							(start 0.2794 0.1778)
							(mid 0.249642 0.249642)
							(end 0.1778 0.2794)
						)
					)
					(width 0)
					(fill yes)
				)
			)
		)
	)
)
